FILE_TYPE = CONNECTIVITY;
{Allegro Design Entry HDL 17.4-2019 S026 (4007227) 1/17/2022}
"PAGE_NUMBER" = 410;
0"NC";
1"GND\g";
2"GND\g";
3"GND\g";
4"GND\g";
5"SMB_RT_CPU0_P1_ROM_R_SDA";
6"SMB_RT_CPU0_P1_ROM_SDA";
7"SMB_RT_CPU0_P1_ROM_R_SCL";
8"SMB_RT_CPU0_P1_ROM_SCL";
9"P1V8_CPU0_RT_1D\g";
10"U15_E2";
%"Q_RES"
"2","(-3075,5375)","0","pure_quanta","I20";
;
LOCATION"R1044"
$SEC"1"
CDS_SEC"1"
WATTAGE"1/20W"
TOLERANCE"1%"
MATERIAL"CHIP"
VALUE"1K"
PACK_TYPE"0201LF"
CDS_LIB"pure_quanta"
PART_NUMBER"CS21001FE07";
"A"
$PN"1"10;
"B"
$PN"2"2;
%"UNIVERSAL_GND"
"1","(-3225,5300)","0","pure_quanta_power","I21";
;
CDS_LIB"pure_quanta_power"
HDL_POWER"GND";
"A"1;
%"UNIVERSAL_GND"
"1","(-3075,4950)","0","pure_quanta_power","I22";
;
CDS_LIB"pure_quanta_power"
HDL_POWER"GND";
"A"2;
%"P1V0"
"1","(-4200,6425)","0","pure_quanta_power","I23";
;
HDL_POWER"P1V8_CPU0_RT_1D"
CDS_LIB"pure_quanta_power";
"A"9;
%"Q_CAP"
"1","(-4500,6075)","0","pure_quanta","I24";
;
LOCATION"C664"
$SEC"1"
CDS_SEC"1"
VALUE"0.1UF"
VOLTAGE"10V"
TOLERANCE"10%"
MATERIAL"X7S"
PACK_TYPE"C0201"
CDS_LIB"pure_quanta"
PART_NUMBER"CH4102K6E00";
"B"
$PN"2"3;
"A"
$PN"1"9;
%"UNIVERSAL_GND"
"1","(-4500,5800)","0","pure_quanta_power","I25";
;
CDS_LIB"pure_quanta_power"
HDL_POWER"GND";
"A"3;
%"UNIVERSAL_GND"
"1","(-4225,5600)","7","pure_quanta_power","I26";
;
CDS_LIB"pure_quanta_power"
HDL_POWER"GND";
"A"4;
%"M24M02DRMN6TP"
"1","(-3750,5575)","0","pure_quanta","I5";
;
LOCATION"U15"
$SEC"1"
CDS_SEC"1"
PART_TYPE"SMLF"
VALUE"M24M02-DRMN6TP"
MATERIAL"IC"
CDS_LIB"pure_quanta"
CDS_LMAN_SYM_OUTLINE"-175,125,175,-125"
NEEDS_NO_SIZE"TRUE"
PART_NUMBER"AKE33Z00600";
"DU1"
$PN"1"0;
"DU2"
$PN"2"0;
"E2"
$PN"3"10;
"VSS"
$PN"4"1;
"SDA"
$PN"5"6;
"SCL"
$PN"6"8;
"WC_N \B"
$PN"7"4;
"VCC"
$PN"8"9;
%"Q_RES"
"1","(-5175,5550)","0","pure_quanta","I6";
;
LOCATION"R678"
$SEC"1"
CDS_SEC"1"
PACK_TYPE"0201LF"
WATTAGE"1/20W"
MATERIAL"CHIP"
VALUE"33.2"
TOLERANCE"1%"
CDS_LIB"pure_quanta"
PART_NUMBER"CS03321FE09";
"B"
$PN"2"8;
"A"
$PN"1"7;
%"Q_RES"
"1","(-5175,5500)","0","pure_quanta","I7";
;
LOCATION"R679"
$SEC"1"
CDS_SEC"1"
MATERIAL"CHIP"
WATTAGE"1/20W"
PACK_TYPE"0201LF"
CDS_LIB"pure_quanta"
VALUE"33.2"
TOLERANCE"1%"
PART_NUMBER"CS03321FE09";
"B"
$PN"2"6;
"A"
$PN"1"5;
END.
